# BASEBOARD_FAB2 (Tioga Pass) — schematic netlist excerpt (pin names and nets, part order shuffled) for the footprints in the layout excerpt that follows; sources: Cadence DE-HDL packaged netlist, KiCad conversion of Wiwynn_Tioga_Pass_MB.brd

J6T1  SCONN288_H44441003  SCONN  pkg PIP  page 44
  \12v\(1)  = P12V_NVDIMM_ABC
  VSS(93)  = GND
  DQ(4)  = M_A_DQ<4>
  VSS(92)  = GND
  DQ(0)  = M_A_DQ<0>
  VSS(91)  = GND
  DQS9P  = M_A_DQS_DP<9>
  DQS9N  = M_A_DQS_DN<9>
  VSS(90)  = GND
  DQ(6)  = M_A_DQ<6>
  VSS(89)  = GND
  DQ(2)  = M_A_DQ<2>
  VSS(88)  = GND
  DQ(12)  = M_A_DQ<12>
  VSS(87)  = GND
  DQ(8)  = M_A_DQ<8>
  VSS(86)  = GND
  DQS10P  = M_A_DQS_DP<10>
  DQS10N  = M_A_DQS_DN<10>
  VSS(85)  = GND
  DQ(14)  = M_A_DQ<14>
  VSS(84)  = GND
  DQ(10)  = M_A_DQ<10>
  VSS(83)  = GND
  DQ(20)  = M_A_DQ<20>
  VSS(82)  = GND
  DQ(16)  = M_A_DQ<16>
  VSS(81)  = GND
  DQS11P  = M_A_DQS_DP<11>
  DQS11N  = M_A_DQS_DN<11>
  VSS(80)  = GND
  DQ(22)  = M_A_DQ<22>
  VSS(79)  = GND
  DQ(18)  = M_A_DQ<18>
  VSS(78)  = GND
  DQ(28)  = M_A_DQ<28>
  VSS(77)  = GND
  DQ(24)  = M_A_DQ<24>
  VSS(76)  = GND
  DQS12P  = M_A_DQS_DP<12>
  DQS12N  = M_A_DQS_DN<12>
  VSS(75)  = GND
  DQ(30)  = M_A_DQ<30>
  VSS(74)  = GND
  DQ(26)  = M_A_DQ<26>
  VSS(73)  = GND
  CB(4)  = M_A_ECC<4>
  VSS(72)  = GND
  CB(0)  = M_A_ECC<0>
  VSS(71)  = GND
  DQS17P  = M_A_DQS_DP<17>
  DQS17N  = M_A_DQS_DN<17>
  VSS(70)  = GND
  CB(6)  = M_A_ECC<6>
  VSS(69)  = GND
  CB(2)  = M_A_ECC<2>
  VSS(68)  = GND
  RESET_N  = M_ABC_RST_N
  VDD(25)  = PVDDQ_ABC
  CKE(0)  = M_A_CKE<2>
  VDD(24)  = PVDDQ_ABC
  ACT_N  = M_A_ACT_N
  BG(0)  = M_A_BG<0>
  VDD(23)  = PVDDQ_ABC
  A12  = M_A_MA<12>
  A9  = M_A_MA<9>
  VDD(22)  = PVDDQ_ABC
  A8  = M_A_MA<8>
  A6  = M_A_MA<6>
  VDD(21)  = PVDDQ_ABC
  A3  = M_A_MA<3>
  A1  = M_A_MA<1>
  VDD(20)  = PVDDQ_ABC
  CK0P  = M_A_CLK_DP<2>
  CK0N  = M_A_CLK_DN<2>
  VDD(19)  = PVDDQ_ABC
  VTT(1)  = PVTT_ABC
  EVENT_N  = FM_DIMM_EVENT_COD_N
  A0  = M_A_MA<0>
  VDD(18)  = PVDDQ_ABC
  BA(0)  = M_A_BA<0>
  A16_RAS_N  = M_A_MA<16>
  VDD(17)  = PVDDQ_ABC
  S0_N  = M_A_CS_N<4>
  VDD(16)  = PVDDQ_ABC
  A15_CAS_N  = M_A_MA<15>
  ODT(0)  = M_A_ODT<2>
  VDD(15)  = PVDDQ_ABC
  S1_N  = M_A_CS_N<5>
  VDD(14)  = PVDDQ_ABC
  ODT(1)  = M_A_ODT<3>
  VDD(13)  = PVDDQ_ABC
  S2_N_C(0)  = M_A_CS_N<6>
  VSS(67)  = GND
  DQ(36)  = M_A_DQ<36>
  VSS(66)  = GND
  DQ(32)  = M_A_DQ<32>
  VSS(65)  = GND
  DQS13P  = M_A_DQS_DP<13>
  DQS13N  = M_A_DQS_DN<13>
  VSS(64)  = GND
  DQ(38)  = M_A_DQ<38>
  VSS(63)  = GND
  DQ(34)  = M_A_DQ<34>
  VSS(62)  = GND
  DQ(44)  = M_A_DQ<44>
  VSS(61)  = GND
  DQ(40)  = M_A_DQ<40>
  VSS(60)  = GND
  DQS14P  = M_A_DQS_DP<14>
  DQS14N  = M_A_DQS_DN<14>
  VSS(59)  = GND
  DQ(46)  = M_A_DQ<46>
  VSS(58)  = GND
  DQ(42)  = M_A_DQ<42>
  VSS(57)  = GND
  DQ(52)  = M_A_DQ<52>
  VSS(56)  = GND
  DQ(48)  = M_A_DQ<48>
  VSS(55)  = GND
  DQS15P  = M_A_DQS_DP<15>
  DQS15N  = M_A_DQS_DN<15>
  VSS(54)  = GND
  DQ(54)  = M_A_DQ<54>
  VSS(53)  = GND
  DQ(50)  = M_A_DQ<50>
  VSS(52)  = GND
  DQ(60)  = M_A_DQ<60>
  VSS(51)  = GND
  DQ(56)  = M_A_DQ<56>
  VSS(50)  = GND
  DQS16P  = M_A_DQS_DP<16>
  DQS16N  = M_A_DQS_DN<16>
  VSS(49)  = GND
  DQ(62)  = M_A_DQ<62>
  VSS(48)  = GND
  DQ(58)  = M_A_DQ<58>
  VSS(47)  = GND
  SA(0)  = PVPP_ABC
  SA(1)  = GND
  SCL  = SMB_DDR_ABC_VPP_SCL
  VPP(4)  = PVPP_ABC
  VPP(3)  = PVPP_ABC
  RFU(2)  = TP_CH_A_DIMM_A1_RFU_2
  \12v\(0)  = P12V_NVDIMM_ABC
  VREFCA  = M_A_VREF
  VSS(46)  = GND
  DQ(5)  = M_A_DQ<5>
  VSS(45)  = GND
  DQ(1)  = M_A_DQ<1>
  VSS(44)  = GND
  DQS0N  = M_A_DQS_DN<0>
  DQS0P  = M_A_DQS_DP<0>
  VSS(43)  = GND
  DQ(7)  = M_A_DQ<7>
  VSS(42)  = GND
  DQ(3)  = M_A_DQ<3>
  VSS(41)  = GND
  DQ(13)  = M_A_DQ<13>
  VSS(40)  = GND
  DQ(9)  = M_A_DQ<9>
  VSS(39)  = GND
  DQS1N  = M_A_DQS_DN<1>
  DQS1P  = M_A_DQS_DP<1>
  VSS(38)  = GND
  DQ(15)  = M_A_DQ<15>
  VSS(37)  = GND
  DQ(11)  = M_A_DQ<11>
  VSS(36)  = GND
  DQ(21)  = M_A_DQ<21>
  VSS(35)  = GND
  DQ(17)  = M_A_DQ<17>
  VSS(34)  = GND
  DQS2N  = M_A_DQS_DN<2>
  DQS2P  = M_A_DQS_DP<2>
  VSS(33)  = GND
  DQ(23)  = M_A_DQ<23>
  VSS(32)  = GND
  DQ(19)  = M_A_DQ<19>
  VSS(31)  = GND
  DQ(29)  = M_A_DQ<29>
  VSS(30)  = GND
  DQ(25)  = M_A_DQ<25>
  VSS(29)  = GND
  DQS3N  = M_A_DQS_DN<3>
  DQS3P  = M_A_DQS_DP<3>
  VSS(28)  = GND
  DQ(31)  = M_A_DQ<31>
  VSS(27)  = GND
  DQ(27)  = M_A_DQ<27>
  VSS(26)  = GND
  CB(5)  = M_A_ECC<5>
  VSS(25)  = GND
  CB(1)  = M_A_ECC<1>
  VSS(24)  = GND
  DQS8N  = M_A_DQS_DN<8>
  DQS8P  = M_A_DQS_DP<8>
  VSS(23)  = GND
  CB(7)  = M_A_ECC<7>
  VSS(22)  = GND
  CB(3)  = M_A_ECC<3>
  VSS(21)  = GND
  CKE(1)  = M_A_CKE<3>
  VDD(12)  = PVDDQ_ABC
  RFU(0)  = TP_CH_A_DIMM_A1_RFU_0
  VDD(11)  = PVDDQ_ABC
  BG(1)  = M_A_BG<1>
  ALERT_N  = M_A_ALERT_N
  VDD(10)  = PVDDQ_ABC
  A11  = M_A_MA<11>
  A7  = M_A_MA<7>
  VDD(9)  = PVDDQ_ABC
  A5  = M_A_MA<5>
  A4  = M_A_MA<4>
  VDD(8)  = PVDDQ_ABC
  A2  = M_A_MA<2>
  VDD(7)  = PVDDQ_ABC
  CK1P  = M_A_CLK_DP<3>
  CK1N  = M_A_CLK_DN<3>
  VDD(6)  = PVDDQ_ABC
  VTT(0)  = PVTT_ABC
  PAR  = M_A_PAR
  VDD(5)  = PVDDQ_ABC
  BA(1)  = M_A_BA<1>
  A10  = M_A_MA<10>
  VDD(4)  = PVDDQ_ABC
  RFU(1)  = TP_CH_A_DIMM_A1_RFU_1
  A14_WE_N  = M_A_MA<14>
  VDD(3)  = PVDDQ_ABC
  SAVE_N_NC  = FM_ADR_COMPLETE_ABC_N
  VDD(2)  = PVDDQ_ABC
  A13  = M_A_MA<13>
  VDD(1)  = PVDDQ_ABC
  A17  = M_A_MA<17>
  C(2)  = M_A_C<2>
  VDD(0)  = PVDDQ_ABC
  S3_N_C(1)  = M_A_CS_N<7>
  SA(2)  = GND
  VSS(20)  = GND
  DQ(37)  = M_A_DQ<37>
  VSS(19)  = GND
  DQ(33)  = M_A_DQ<33>
  VSS(18)  = GND
  DQS4N  = M_A_DQS_DN<4>
  DQS4P  = M_A_DQS_DP<4>
  VSS(17)  = GND
  DQ(39)  = M_A_DQ<39>
  VSS(16)  = GND
  DQ(35)  = M_A_DQ<35>
  VSS(15)  = GND
  DQ(45)  = M_A_DQ<45>
  VSS(14)  = GND
  DQ(41)  = M_A_DQ<41>
  VSS(13)  = GND
  DQS5N  = M_A_DQS_DN<5>
  DQS5P  = M_A_DQS_DP<5>
  VSS(12)  = GND
  DQ(47)  = M_A_DQ<47>
  VSS(11)  = GND
  DQ(43)  = M_A_DQ<43>
  VSS(10)  = GND
  DQ(53)  = M_A_DQ<53>
  VSS(9)  = GND
  DQ(49)  = M_A_DQ<49>
  VSS(8)  = GND
  DQS6N  = M_A_DQS_DN<6>
  DQS6P  = M_A_DQS_DP<6>
  VSS(7)  = GND
  DQ(55)  = M_A_DQ<55>
  VSS(6)  = GND
  DQ(51)  = M_A_DQ<51>
  VSS(5)  = GND
  DQ(61)  = M_A_DQ<61>
  VSS(4)  = GND
  DQ(57)  = M_A_DQ<57>
  VSS(3)  = GND
  DQS7N  = M_A_DQS_DN<7>
  DQS7P  = M_A_DQS_DP<7>
  VSS(2)  = GND
  DQ(63)  = M_A_DQ<63>
  VSS(1)  = GND
  DQ(59)  = M_A_DQ<59>
  VSS(0)  = GND
  VDDSPD  = PVPP_ABC
  SDA  = SMB_DDR_ABC_VPP_SDA
  VPP(1)  = PVPP_ABC
  VPP(0)  = PVPP_ABC
  VPP(2)  = PVPP_ABC

(kicad_pcb
	(version 20260206)
	(generator "pcbnew")
	(generator_version "10.0")
	(general
		(thickness 1.6)
		(legacy_teardrops no)
	)
	(paper "A4")
	(title_block
		(title "Wiwynn_Tioga_Pass_MB.brd")
		(comment 1 "Tioga Pass / footprint 3283 of 4770 (J6T1), pads 202-249 of 291")
	)
	(layers
		(0 "F.Cu" signal "TOP")
		(4 "In1.Cu" signal "L2GND")
		(6 "In2.Cu" signal "L3")
		(8 "In3.Cu" signal "L4GND")
		(10 "In4.Cu" signal "L5")
		(12 "In5.Cu" signal "L6GND")
		(14 "In6.Cu" signal "L7VCC")
		(16 "In7.Cu" signal "L8VCC")
		(18 "In8.Cu" signal "L9GND")
		(20 "In9.Cu" signal "L10")
		(22 "In10.Cu" signal "L11GND")
		(24 "In11.Cu" signal "L12")
		(26 "In12.Cu" signal "L13GND")
		(2 "B.Cu" signal "BOTTOM")
		(9 "F.Adhes" user "F.Adhesive")
		(11 "B.Adhes" user "B.Adhesive")
		(13 "F.Paste" user "Package Geometry/Pastemask Top")
		(15 "B.Paste" user "Package Geometry/Pastemask Bottom")
		(5 "F.SilkS" user "Ref Des/Silkscreen Top")
		(7 "B.SilkS" user "Ref Des/Silkscreen Bottom")
		(1 "F.Mask" user "Board Geometry/Soldermask Top")
		(3 "B.Mask" user "Board Geometry/Soldermask Bottom")
		(17 "Dwgs.User" user "User.Drawings")
		(19 "Cmts.User" user "User.Comments")
		(21 "Eco1.User" user "User.Eco1")
		(23 "Eco2.User" user "User.Eco2")
		(25 "Edge.Cuts" user "Board Geometry/Outline")
		(27 "Margin" user)
		(31 "F.CrtYd" user "Package Geometry/Place Bound Top")
		(29 "B.CrtYd" user "Package Geometry/Place Bound Bottom")
		(35 "F.Fab" user "Ref Des/Assembly Top")
		(33 "B.Fab" user "Ref Des/Assembly Bottom")
	)
	(footprint ""
		(layer "B.Cu")
		(at 194.700398 -24.824182 90)
		(property "Reference" "J6T1"
			(at 2.200148 39.23411 0)
			(unlocked yes)
			(layer "B.SilkS")
			(effects
				(font
					(size 0.7874 0.5842)
					(thickness 0.1524)
				)
				(justify left mirror)
			)
		)
		(property "Value" ""
			(at 0 0 90)
			(layer "B.Fab")
			(effects
				(font
					(size 1.27 1.27)
				)
				(justify mirror)
			)
		)
		(duplicate_pad_numbers_are_jumpers no)
		(pad "199" smd rect
			(at -4.59994 45.900086 270)
			(size 1.8034 0.508)
			(layers "B.Cu" "B.Mask" "B.Paste")
			(net "M_A_ECC<7>")
		)
		(pad "200" smd rect
			(at -4.59994 46.74997 270)
			(size 1.8034 0.508)
			(layers "B.Cu" "B.Mask" "B.Paste")
			(net "GND")
		)
		(pad "201" smd rect
			(at -4.59994 47.600108 270)
			(size 1.8034 0.508)
			(layers "B.Cu" "B.Mask" "B.Paste")
			(net "M_A_ECC<3>")
		)
		(pad "202" smd rect
			(at -4.59994 48.449992 270)
			(size 1.8034 0.508)
			(layers "B.Cu" "B.Mask" "B.Paste")
			(net "GND")
		)
		(pad "203" smd rect
			(at -4.59994 49.299876 270)
			(size 1.8034 0.508)
			(layers "B.Cu" "B.Mask" "B.Paste")
			(net "M_A_CKE<3>")
		)
		(pad "204" smd rect
			(at -4.59994 50.150014 270)
			(size 1.8034 0.508)
			(layers "B.Cu" "B.Mask" "B.Paste")
			(net "PVDDQ_ABC")
		)
		(pad "205" smd rect
			(at -4.59994 50.999898 270)
			(size 1.8034 0.508)
			(layers "B.Cu" "B.Mask" "B.Paste")
			(net "TP_CH_A_DIMM_A1_RFU_0")
		)
		(pad "206" smd rect
			(at -4.59994 51.850036 270)
			(size 1.8034 0.508)
			(layers "B.Cu" "B.Mask" "B.Paste")
			(net "PVDDQ_ABC")
		)
		(pad "207" smd rect
			(at -4.59994 52.69992 270)
			(size 1.8034 0.508)
			(layers "B.Cu" "B.Mask" "B.Paste")
			(net "M_A_BG<1>")
		)
		(pad "208" smd rect
			(at -4.59994 53.550058 270)
			(size 1.8034 0.508)
			(layers "B.Cu" "B.Mask" "B.Paste")
			(net "M_A_ALERT_N")
		)
		(pad "209" smd rect
			(at -4.59994 54.399942 270)
			(size 1.8034 0.508)
			(layers "B.Cu" "B.Mask" "B.Paste")
			(net "PVDDQ_ABC")
		)
		(pad "210" smd rect
			(at -4.59994 55.25008 270)
			(size 1.8034 0.508)
			(layers "B.Cu" "B.Mask" "B.Paste")
			(net "M_A_MA<11>")
		)
		(pad "211" smd rect
			(at -4.59994 56.099964 270)
			(size 1.8034 0.508)
			(layers "B.Cu" "B.Mask" "B.Paste")
			(net "M_A_MA<7>")
		)
		(pad "212" smd rect
			(at -4.59994 56.950102 270)
			(size 1.8034 0.508)
			(layers "B.Cu" "B.Mask" "B.Paste")
			(net "PVDDQ_ABC")
		)
		(pad "213" smd rect
			(at -4.59994 57.799986 270)
			(size 1.8034 0.508)
			(layers "B.Cu" "B.Mask" "B.Paste")
			(net "M_A_MA<5>")
		)
		(pad "214" smd rect
			(at -4.59994 58.650124 270)
			(size 1.8034 0.508)
			(layers "B.Cu" "B.Mask" "B.Paste")
			(net "M_A_MA<4>")
		)
		(pad "215" smd rect
			(at -4.59994 59.500008 270)
			(size 1.8034 0.508)
			(layers "B.Cu" "B.Mask" "B.Paste")
			(net "PVDDQ_ABC")
		)
		(pad "216" smd rect
			(at -4.59994 60.349892 270)
			(size 1.8034 0.508)
			(layers "B.Cu" "B.Mask" "B.Paste")
			(net "M_A_MA<2>")
		)
		(pad "217" smd rect
			(at -4.59994 61.20003 270)
			(size 1.8034 0.508)
			(layers "B.Cu" "B.Mask" "B.Paste")
			(net "PVDDQ_ABC")
		)
		(pad "218" smd rect
			(at -4.59994 62.049914 270)
			(size 1.8034 0.508)
			(layers "B.Cu" "B.Mask" "B.Paste")
			(net "M_A_CLK_DP<3>")
		)
		(pad "219" smd rect
			(at -4.59994 62.900052 270)
			(size 1.8034 0.508)
			(layers "B.Cu" "B.Mask" "B.Paste")
			(net "M_A_CLK_DN<3>")
		)
		(pad "220" smd rect
			(at -4.59994 63.749936 270)
			(size 1.8034 0.508)
			(layers "B.Cu" "B.Mask" "B.Paste")
			(net "PVDDQ_ABC")
		)
		(pad "221" smd rect
			(at -4.59994 64.600074 270)
			(size 1.8034 0.508)
			(layers "B.Cu" "B.Mask" "B.Paste")
			(net "PVTT_ABC")
		)
		(pad "222" smd rect
			(at -4.59994 70.550024 270)
			(size 1.8034 0.508)
			(layers "B.Cu" "B.Mask" "B.Paste")
			(net "M_A_PAR")
		)
		(pad "223" smd rect
			(at -4.59994 71.399908 270)
			(size 1.8034 0.508)
			(layers "B.Cu" "B.Mask" "B.Paste")
			(net "PVDDQ_ABC")
		)
		(pad "224" smd rect
			(at -4.59994 72.250046 270)
			(size 1.8034 0.508)
			(layers "B.Cu" "B.Mask" "B.Paste")
			(net "M_A_BA<1>")
		)
		(pad "225" smd rect
			(at -4.59994 73.09993 270)
			(size 1.8034 0.508)
			(layers "B.Cu" "B.Mask" "B.Paste")
			(net "M_A_MA<10>")
		)
		(pad "226" smd rect
			(at -4.59994 73.950068 270)
			(size 1.8034 0.508)
			(layers "B.Cu" "B.Mask" "B.Paste")
			(net "PVDDQ_ABC")
		)
		(pad "227" smd rect
			(at -4.59994 74.799952 270)
			(size 1.8034 0.508)
			(layers "B.Cu" "B.Mask" "B.Paste")
			(net "TP_CH_A_DIMM_A1_RFU_1")
		)
		(pad "228" smd rect
			(at -4.59994 75.65009 270)
			(size 1.8034 0.508)
			(layers "B.Cu" "B.Mask" "B.Paste")
			(net "M_A_MA<14>")
		)
		(pad "229" smd rect
			(at -4.59994 76.499974 270)
			(size 1.8034 0.508)
			(layers "B.Cu" "B.Mask" "B.Paste")
			(net "PVDDQ_ABC")
		)
		(pad "230" smd rect
			(at -4.59994 77.350112 270)
			(size 1.8034 0.508)
			(layers "B.Cu" "B.Mask" "B.Paste")
			(net "FM_ADR_COMPLETE_ABC_N")
		)
		(pad "231" smd rect
			(at -4.59994 78.199996 270)
			(size 1.8034 0.508)
			(layers "B.Cu" "B.Mask" "B.Paste")
			(net "PVDDQ_ABC")
		)
		(pad "232" smd rect
			(at -4.59994 79.04988 270)
			(size 1.8034 0.508)
			(layers "B.Cu" "B.Mask" "B.Paste")
			(net "M_A_MA<13>")
		)
		(pad "233" smd rect
			(at -4.59994 79.900018 270)
			(size 1.8034 0.508)
			(layers "B.Cu" "B.Mask" "B.Paste")
			(net "PVDDQ_ABC")
		)
		(pad "234" smd rect
			(at -4.59994 80.749902 270)
			(size 1.8034 0.508)
			(layers "B.Cu" "B.Mask" "B.Paste")
			(net "M_A_MA<17>")
		)
		(pad "235" smd rect
			(at -4.59994 81.60004 270)
			(size 1.8034 0.508)
			(layers "B.Cu" "B.Mask" "B.Paste")
			(net "M_A_C<2>")
		)
		(pad "236" smd rect
			(at -4.59994 82.449924 270)
			(size 1.8034 0.508)
			(layers "B.Cu" "B.Mask" "B.Paste")
			(net "PVDDQ_ABC")
		)
		(pad "237" smd rect
			(at -4.59994 83.300062 270)
			(size 1.8034 0.508)
			(layers "B.Cu" "B.Mask" "B.Paste")
			(net "M_A_CS_N<7>")
		)
		(pad "238" smd rect
			(at -4.59994 84.149946 270)
			(size 1.8034 0.508)
			(layers "B.Cu" "B.Mask" "B.Paste")
			(net "GND")
		)
		(pad "239" smd rect
			(at -4.59994 85.000084 270)
			(size 1.8034 0.508)
			(layers "B.Cu" "B.Mask" "B.Paste")
			(net "GND")
		)
		(pad "240" smd rect
			(at -4.59994 85.849968 270)
			(size 1.8034 0.508)
			(layers "B.Cu" "B.Mask" "B.Paste")
			(net "M_A_DQ<37>")
		)
		(pad "241" smd rect
			(at -4.59994 86.700106 270)
			(size 1.8034 0.508)
			(layers "B.Cu" "B.Mask" "B.Paste")
			(net "GND")
		)
		(pad "242" smd rect
			(at -4.59994 87.54999 270)
			(size 1.8034 0.508)
			(layers "B.Cu" "B.Mask" "B.Paste")
			(net "M_A_DQ<33>")
		)
		(pad "243" smd rect
			(at -4.59994 88.399874 270)
			(size 1.8034 0.508)
			(layers "B.Cu" "B.Mask" "B.Paste")
			(net "GND")
		)
		(pad "244" smd rect
			(at -4.59994 89.250012 270)
			(size 1.8034 0.508)
			(layers "B.Cu" "B.Mask" "B.Paste")
			(net "M_A_DQS_DN<4>")
		)
		(pad "245" smd rect
			(at -4.59994 90.099896 270)
			(size 1.8034 0.508)
			(layers "B.Cu" "B.Mask" "B.Paste")
			(net "M_A_DQS_DP<4>")
		)
		(pad "246" smd rect
			(at -4.59994 90.950034 270)
			(size 1.8034 0.508)
			(layers "B.Cu" "B.Mask" "B.Paste")
			(net "GND")
		)
	)
)
